(kicad_pcb
	(version 20260206)
	(generator "pcbnew")
	(generator_version "10.0")
	(general
		(thickness 1.6)
		(legacy_teardrops no)
	)
	(paper "A4")
	(title_block
		(title "dpb — 14545-sa.0730WZS0815.brd")
		(comment 1 "Honey Badger (Wiwynn) / footprints 287-290 of 1066")
	)
	(layers
		(0 "F.Cu" signal "TOP")
		(4 "In1.Cu" signal "L2GND")
		(6 "In2.Cu" signal "L3")
		(8 "In3.Cu" signal "L4VCC")
		(10 "In4.Cu" signal "L5VCC")
		(12 "In5.Cu" signal "L6")
		(14 "In6.Cu" signal "L7GND")
		(2 "B.Cu" signal "BOTTOM")
		(9 "F.Adhes" user "F.Adhesive")
		(11 "B.Adhes" user "B.Adhesive")
		(13 "F.Paste" user "Package Geometry/Pastemask Top")
		(15 "B.Paste" user "Package Geometry/Pastemask Bottom")
		(5 "F.SilkS" user "Ref Des/Silkscreen Top")
		(7 "B.SilkS" user "Ref Des/Silkscreen Bottom")
		(1 "F.Mask" user "Board Geometry/Soldermask Top")
		(3 "B.Mask" user "Board Geometry/Soldermask Bottom")
		(17 "Dwgs.User" user "User.Drawings")
		(19 "Cmts.User" user "User.Comments")
		(21 "Eco1.User" user "User.Eco1")
		(23 "Eco2.User" user "User.Eco2")
		(25 "Edge.Cuts" user "Board Geometry/Outline")
		(27 "Margin" user)
		(31 "F.CrtYd" user "Package Geometry/Place Bound Top")
		(29 "B.CrtYd" user "Package Geometry/Place Bound Bottom")
		(35 "F.Fab" user "Ref Des/Assembly Top")
		(33 "B.Fab" user "Ref Des/Assembly Bottom")
	)
	(footprint ""
		(layer "F.Cu")
		(at 28.50007 -379.240034 180)
		(property "Reference" "U46"
			(at 0 0 180)
			(layer "F.SilkS")
			(hide yes)
			(effects
				(font
					(size 1.27 1.27)
				)
			)
		)
		(property "Value" "TMP75AIDGKR-GP"
			(at -0.1143 -9.1948 180)
			(unlocked yes)
			(layer "F.Fab")
			(hide yes)
			(effects
				(font
					(size 1.016 1.016)
					(thickness 0.1524)
				)
			)
		)
		(property "Device Type" "MSOP8-1H44"
			(at -0.1143 -10.795 180)
			(unlocked yes)
			(layer "F.Fab")
			(hide yes)
			(effects
				(font
					(size 1.016 1.016)
					(thickness 0.1524)
				)
			)
		)
		(duplicate_pad_numbers_are_jumpers no)
		(fp_line
			(start 1.0795 1.016)
			(end 1.0795 -1.016)
			(stroke
				(width 0.1524)
				(type default)
			)
			(layer "F.SilkS")
		)
		(fp_line
			(start 1.0795 -1.016)
			(end -1.9558 -1.016)
			(stroke
				(width 0.1524)
				(type default)
			)
			(layer "F.SilkS")
		)
		(fp_line
			(start -1.4478 -0.0381)
			(end -1.9558 0.4699)
			(stroke
				(width 0.1524)
				(type default)
			)
			(layer "F.SilkS")
		)
		(fp_line
			(start -1.778 1.0922)
			(end -1.778 3.048)
			(stroke
				(width 0.508)
				(type default)
			)
			(layer "F.SilkS")
		)
		(fp_line
			(start -1.9558 1.016)
			(end 1.0795 1.016)
			(stroke
				(width 0.1524)
				(type default)
			)
			(layer "F.SilkS")
		)
		(fp_line
			(start -1.9558 -0.5461)
			(end -1.4478 -0.0381)
			(stroke
				(width 0.1524)
				(type default)
			)
			(layer "F.SilkS")
		)
		(fp_line
			(start -1.9558 -1.016)
			(end -1.9558 1.016)
			(stroke
				(width 0.1524)
				(type default)
			)
			(layer "F.SilkS")
		)
		(fp_poly
			(pts
				(xy -1.1557 -1.016) (xy -1.1557 1.016) (xy 1.1557 1.016) (xy 1.1557 -1.016)
			)
			(stroke
				(width 0)
				(type default)
			)
			(fill yes)
			(layer "F.SilkS")
		)
		(fp_rect
			(start -1.4986 2.4511)
			(end 1.4986 -2.4511)
			(stroke
				(width 0)
				(type default)
			)
			(fill no)
			(layer "F.CrtYd")
		)
		(fp_poly
			(pts
				(xy -2.032 3.302) (xy -2.032 -3.302) (xy 2.032 -3.302) (xy 2.032 -2.1209) (xy 1.4986 -2.1209) (xy 1.4986 -2.4511)
				(xy -1.4986 -2.4511) (xy -1.4986 2.4511) (xy 1.4986 2.4511) (xy 1.4986 -2.1082) (xy 2.032 -2.1082)
				(xy 2.032 3.302)
			)
			(stroke
				(width 0)
				(type default)
			)
			(fill no)
			(layer "F.CrtYd")
		)
		(fp_rect
			(start -2.032 3.302)
			(end 2.032 -3.302)
			(stroke
				(width 0)
				(type default)
			)
			(fill no)
			(layer "F.Fab")
		)
		(pad "1" smd rect
			(at -0.97536 2.05486 180)
			(size 0.3556 1.524)
			(layers "F.Cu" "F.Mask" "F.Paste")
			(net "TMP1_SDA")
		)
		(pad "2" smd rect
			(at -0.32512 2.05486 180)
			(size 0.3556 1.524)
			(layers "F.Cu" "F.Mask" "F.Paste")
			(net "TMP1_SCL")
		)
		(pad "3" smd rect
			(at 0.32512 2.05486 180)
			(size 0.3556 1.524)
			(layers "F.Cu" "F.Mask" "F.Paste")
			(net "I2C_B_TMP1_ALERT")
		)
		(pad "4" smd rect
			(at 0.97536 2.05486 180)
			(size 0.3556 1.524)
			(layers "F.Cu" "F.Mask" "F.Paste")
			(net "GND")
		)
		(pad "5" smd rect
			(at 0.97536 -2.05486 180)
			(size 0.3556 1.524)
			(layers "F.Cu" "F.Mask" "F.Paste")
			(net "I2C_B_TMP1_A2")
		)
		(pad "6" smd rect
			(at 0.32512 -2.05486 180)
			(size 0.3556 1.524)
			(layers "F.Cu" "F.Mask" "F.Paste")
			(net "I2C_B_TMP1_A1")
		)
		(pad "7" smd rect
			(at -0.32512 -2.05486 180)
			(size 0.3556 1.524)
			(layers "F.Cu" "F.Mask" "F.Paste")
			(net "I2C_B_TMP1_A0")
		)
		(pad "8" smd rect
			(at -0.97536 -2.05486 180)
			(size 0.3556 1.524)
			(layers "F.Cu" "F.Mask" "F.Paste")
			(net "P3V3")
		)
	)
	(footprint ""
		(layer "F.Cu")
		(at 215.263984 -188.488828 180)
		(property "Reference" "C161"
			(at 0 0 180)
			(layer "F.SilkS")
			(hide yes)
			(effects
				(font
					(size 1.27 1.27)
				)
			)
		)
		(property "Value" "SC10U25V6KX-1GP"
			(at -0.0762 -5.1308 180)
			(unlocked yes)
			(layer "F.Fab")
			(hide yes)
			(effects
				(font
					(size 1.016 1.016)
					(thickness 0.1524)
				)
			)
		)
		(property "Device Type" "C1206H71"
			(at -0.127 -6.6548 180)
			(unlocked yes)
			(layer "F.Fab")
			(hide yes)
			(effects
				(font
					(size 1.016 1.016)
					(thickness 0.1524)
				)
			)
		)
		(duplicate_pad_numbers_are_jumpers no)
		(fp_line
			(start 1.016 2.2352)
			(end -1.016 2.2352)
			(stroke
				(width 0.1524)
				(type default)
			)
			(layer "F.SilkS")
		)
		(fp_line
			(start 1.016 0.8382)
			(end 1.016 2.2352)
			(stroke
				(width 0.1524)
				(type default)
			)
			(layer "F.SilkS")
		)
		(fp_line
			(start 1.016 -2.2352)
			(end 1.016 -0.8382)
			(stroke
				(width 0.1524)
				(type default)
			)
			(layer "F.SilkS")
		)
		(fp_line
			(start -1.016 2.2352)
			(end -1.016 0.8382)
			(stroke
				(width 0.1524)
				(type default)
			)
			(layer "F.SilkS")
		)
		(fp_line
			(start -1.016 -0.8382)
			(end -1.016 -2.2352)
			(stroke
				(width 0.1524)
				(type default)
			)
			(layer "F.SilkS")
		)
		(fp_line
			(start -1.016 -2.2352)
			(end 1.016 -2.2352)
			(stroke
				(width 0.1524)
				(type default)
			)
			(layer "F.SilkS")
		)
		(fp_rect
			(start -1.0922 2.3114)
			(end 1.0922 -2.3114)
			(stroke
				(width 0)
				(type default)
			)
			(fill no)
			(layer "F.CrtYd")
		)
		(fp_poly
			(pts
				(xy 1.0922 -2.3114) (xy 1.0922 2.3114) (xy -1.0922 2.3114) (xy -1.0922 -2.3114)
			)
			(stroke
				(width 0)
				(type default)
			)
			(fill no)
			(layer "F.Fab")
		)
		(pad "1" smd rect
			(at 0 -1.397 180)
			(size 1.651 1.27)
			(layers "F.Cu" "F.Mask" "F.Paste")
			(net "P12V_HDD3")
		)
		(pad "2" smd rect
			(at 0 1.397 180)
			(size 1.651 1.27)
			(layers "F.Cu" "F.Mask" "F.Paste")
			(net "GND")
		)
	)
	(footprint ""
		(layer "F.Cu")
		(at 5.969 -34.036 -90)
		(property "Reference" "PC47"
			(at 0 0 270)
			(layer "F.SilkS")
			(hide yes)
			(effects
				(font
					(size 1.27 1.27)
				)
			)
		)
		(property "Value" "SC22U25V5MX-GP"
			(at -0.0762 -6.1214 270)
			(unlocked yes)
			(layer "F.Fab")
			(hide yes)
			(effects
				(font
					(size 1.016 1.016)
					(thickness 0.1524)
				)
			)
		)
		(property "Device Type" "C805H58"
			(at -0.0762 -8.1534 270)
			(unlocked yes)
			(layer "F.Fab")
			(hide yes)
			(effects
				(font
					(size 1.016 1.016)
					(thickness 0.1524)
				)
			)
		)
		(duplicate_pad_numbers_are_jumpers no)
		(fp_line
			(start 0.635 0)
			(end -0.635 0)
			(stroke
				(width 0.508)
				(type default)
			)
			(layer "F.SilkS")
		)
		(fp_rect
			(start -0.9652 1.778)
			(end 0.9652 -1.778)
			(stroke
				(width 0)
				(type default)
			)
			(fill no)
			(layer "F.CrtYd")
		)
		(fp_poly
			(pts
				(xy -0.9652 -1.778) (xy 0.9652 -1.778) (xy 0.9652 1.778) (xy -0.9652 1.778)
			)
			(stroke
				(width 0)
				(type default)
			)
			(fill no)
			(layer "F.Fab")
		)
		(pad "1" smd rect
			(at 0 -0.9652 270)
			(size 1.397 1.143)
			(layers "F.Cu" "F.Mask" "F.Paste")
			(net "P12V")
		)
		(pad "2" smd rect
			(at 0 0.9652 270)
			(size 1.397 1.143)
			(layers "F.Cu" "F.Mask" "F.Paste")
			(net "GND")
		)
	)
	(footprint ""
		(layer "F.Cu")
		(at 93.8022 -18.8214 180)
		(property "Reference" "C324"
			(at 0 0 180)
			(layer "F.SilkS")
			(hide yes)
			(effects
				(font
					(size 1.27 1.27)
				)
			)
		)
		(property "Value" "SCD1U10V2KX-5GP"
			(at 1.1811 -2.7051 180)
			(unlocked yes)
			(layer "F.Fab")
			(hide yes)
			(effects
				(font
					(size 1.016 1.016)
					(thickness 0.1524)
				)
			)
		)
		(property "Device Type" "C402H22"
			(at 1.1811 -4.2291 180)
			(unlocked yes)
			(layer "F.Fab")
			(hide yes)
			(effects
				(font
					(size 1.016 1.016)
					(thickness 0.1524)
				)
			)
		)
		(duplicate_pad_numbers_are_jumpers no)
		(fp_rect
			(start -0.4318 0.9525)
			(end 0.4318 -0.9525)
			(stroke
				(width 0)
				(type default)
			)
			(fill no)
			(layer "F.CrtYd")
		)
		(fp_rect
			(start -0.4318 0.9525)
			(end 0.4318 -0.9525)
			(stroke
				(width 0)
				(type default)
			)
			(fill no)
			(layer "F.Fab")
		)
		(pad "1" smd custom
			(at 0 -0.4445 180)
			(size 0.1524 0.1524)
			(layers "F.Cu" "F.Mask" "F.Paste")
			(net "P3V3")
			(options
				(clearance outline)
				(anchor circle)
			)
			(primitives
				(gr_poly
					(pts
						(arc
							(start 0.3048 -0.2032)
							(mid 0.275042 -0.275042)
							(end 0.2032 -0.3048)
						)
						(arc
							(start -0.2032 -0.3048)
							(mid -0.275042 -0.275042)
							(end -0.3048 -0.2032)
						)
						(arc
							(start -0.3048 0.2032)
							(mid -0.275042 0.275042)
							(end -0.2032 0.3048)
						)
						(arc
							(start 0.2032 0.3048)
							(mid 0.275042 0.275042)
							(end 0.3048 0.2032)
						)
					)
					(width 0)
					(fill yes)
				)
			)
		)
		(pad "2" smd custom
			(at 0 0.4445 180)
			(size 0.1524 0.1524)
			(layers "F.Cu" "F.Mask" "F.Paste")
			(net "GND")
			(options
				(clearance outline)
				(anchor circle)
			)
			(primitives
				(gr_poly
					(pts
						(arc
							(start 0.3048 -0.2032)
							(mid 0.275042 -0.275042)
							(end 0.2032 -0.3048)
						)
						(arc
							(start -0.2032 -0.3048)
							(mid -0.275042 -0.275042)
							(end -0.3048 -0.2032)
						)
						(arc
							(start -0.3048 0.2032)
							(mid -0.275042 0.275042)
							(end -0.2032 0.3048)
						)
						(arc
							(start 0.2032 0.3048)
							(mid 0.275042 0.275042)
							(end 0.3048 0.2032)
						)
					)
					(width 0)
					(fill yes)
				)
			)
		)
	)
)
